# S9S_MB_2U (Grand Teton) — schematic netlist excerpt (pin names and nets, part order shuffled) for the footprints in the layout excerpt that follows; sources: Cadence DE-HDL packaged netlist, KiCad conversion of 03242023_DA0F0TMBIJ0_F0T_Motherboard_J_brd_V01_OCP.brd

PR299  Q_RES  2.2 1% CHIP  pkg 0402LF  page 286 : A = PVCCIN_CPU1_PVCC ; B = PVCCIN_CPU1_VDD4
C1260  Q_CAP  10UF 6.3V 20% X6S  pkg C0603  page 189 : A = P1V05_PCH_PLL_AUX ; B = GND
PC1187_P0_3  Q_CAP  22UF 4V 20% X6S  pkg C0805  page 272 : A = PVCCFA_EHV_FIVRA_CPU0 ; B = GND

(kicad_pcb
	(version 20260206)
	(generator "pcbnew")
	(generator_version "10.0")
	(general
		(thickness 1.6)
		(legacy_teardrops no)
	)
	(paper "A4")
	(title_block
		(title "03242023_DA0F0TMBIJ0_F0T_Motherboard_J_brd_V01_OCP.brd")
		(comment 1 "Grand Teton / footprints 5181-5183 of 6105")
	)
	(layers
		(0 "F.Cu" signal "TOP")
		(4 "In1.Cu" signal "GND")
		(6 "In2.Cu" signal "IN1")
		(8 "In3.Cu" signal "GND1")
		(10 "In4.Cu" signal "IN2")
		(12 "In5.Cu" signal "GND2")
		(14 "In6.Cu" signal "IN3")
		(16 "In7.Cu" signal "GND3")
		(18 "In8.Cu" signal "VCC")
		(20 "In9.Cu" signal "VCC1")
		(22 "In10.Cu" signal "GND4")
		(24 "In11.Cu" signal "IN4")
		(26 "In12.Cu" signal "GND5")
		(28 "In13.Cu" signal "IN5")
		(30 "In14.Cu" signal "GND6")
		(32 "In15.Cu" signal "IN6")
		(34 "In16.Cu" signal "GND7")
		(2 "B.Cu" signal "BOTTOM")
		(9 "F.Adhes" user "F.Adhesive")
		(11 "B.Adhes" user "B.Adhesive")
		(13 "F.Paste" user "Package Geometry/Pastemask Top")
		(15 "B.Paste" user "Package Geometry/Pastemask Bottom")
		(5 "F.SilkS" user "Ref Des/Silkscreen Top")
		(7 "B.SilkS" user "Ref Des/Silkscreen Bottom")
		(1 "F.Mask" user "Board Geometry/Soldermask Top")
		(3 "B.Mask" user "Board Geometry/Soldermask Bottom")
		(17 "Dwgs.User" user "User.Drawings")
		(19 "Cmts.User" user "User.Comments")
		(21 "Eco1.User" user "User.Eco1")
		(23 "Eco2.User" user "User.Eco2")
		(25 "Edge.Cuts" user "Board Geometry/Outline")
		(27 "Margin" user)
		(31 "F.CrtYd" user "Package Geometry/Place Bound Top")
		(29 "B.CrtYd" user "Package Geometry/Place Bound Bottom")
		(35 "F.Fab" user "Ref Des/Assembly Top")
		(33 "B.Fab" user "Ref Des/Assembly Bottom")
	)
	(footprint ""
		(layer "B.Cu")
		(at 119.07266 -334.693514 -90)
		(property "Reference" "PR299"
			(at 0 0 90)
			(layer "B.SilkS")
			(hide yes)
			(effects
				(font
					(size 1.27 1.27)
				)
				(justify mirror)
			)
		)
		(property "Value" ""
			(at 0 0 90)
			(layer "B.Fab")
			(effects
				(font
					(size 1.27 1.27)
				)
				(justify mirror)
			)
		)
		(duplicate_pad_numbers_are_jumpers no)
		(fp_line
			(start -0.7874 0.4064)
			(end 0.7874 0.4064)
			(stroke
				(width 0.1524)
				(type default)
			)
			(layer "B.SilkS")
		)
		(fp_line
			(start 0.7874 0.4064)
			(end 0.7874 -0.4064)
			(stroke
				(width 0.1524)
				(type default)
			)
			(layer "B.SilkS")
		)
		(fp_line
			(start -0.7874 -0.4064)
			(end -0.7874 0.4064)
			(stroke
				(width 0.1524)
				(type default)
			)
			(layer "B.SilkS")
		)
		(fp_line
			(start 0.7874 -0.4064)
			(end -0.7874 -0.4064)
			(stroke
				(width 0.1524)
				(type default)
			)
			(layer "B.SilkS")
		)
		(fp_line
			(start -0.67945 0.3048)
			(end -0.120396 0.3048)
			(stroke
				(width 0.1)
				(type default)
			)
			(layer "B.Fab")
		)
		(fp_line
			(start -0.120396 0.3048)
			(end -0.120396 0.2794)
			(stroke
				(width 0.1)
				(type default)
			)
			(layer "B.Fab")
		)
		(fp_line
			(start 0.12065 0.3048)
			(end 0.67945 0.3048)
			(stroke
				(width 0.1)
				(type default)
			)
			(layer "B.Fab")
		)
		(fp_line
			(start 0.67945 0.3048)
			(end 0.67945 -0.305054)
			(stroke
				(width 0.1)
				(type default)
			)
			(layer "B.Fab")
		)
		(fp_line
			(start -0.120396 0.2794)
			(end 0.12065 0.2794)
			(stroke
				(width 0.1)
				(type default)
			)
			(layer "B.Fab")
		)
		(fp_line
			(start 0.12065 0.2794)
			(end 0.12065 0.3048)
			(stroke
				(width 0.1)
				(type default)
			)
			(layer "B.Fab")
		)
		(fp_line
			(start -0.12065 -0.2794)
			(end -0.12065 -0.3048)
			(stroke
				(width 0.1)
				(type default)
			)
			(layer "B.Fab")
		)
		(fp_line
			(start 0.12065 -0.2794)
			(end -0.12065 -0.2794)
			(stroke
				(width 0.1)
				(type default)
			)
			(layer "B.Fab")
		)
		(fp_line
			(start -0.67945 -0.3048)
			(end -0.67945 0.3048)
			(stroke
				(width 0.1)
				(type default)
			)
			(layer "B.Fab")
		)
		(fp_line
			(start -0.12065 -0.3048)
			(end -0.67945 -0.3048)
			(stroke
				(width 0.1)
				(type default)
			)
			(layer "B.Fab")
		)
		(fp_line
			(start 0.12065 -0.305054)
			(end 0.12065 -0.2794)
			(stroke
				(width 0.1)
				(type default)
			)
			(layer "B.Fab")
		)
		(fp_line
			(start 0.67945 -0.305054)
			(end 0.12065 -0.305054)
			(stroke
				(width 0.1)
				(type default)
			)
			(layer "B.Fab")
		)
		(pad "1" smd circle
			(at 0.40005 0 90)
			(size 0 0)
			(layers "B.Cu" "B.Mask" "B.Paste")
			(net "PVCCIN_CPU1_PVCC")
		)
		(pad "2" smd circle
			(at -0.40005 0 90)
			(size 0 0)
			(layers "B.Cu" "B.Mask" "B.Paste")
			(net "PVCCIN_CPU1_VDD4")
		)
	)
	(footprint ""
		(layer "B.Cu")
		(at 422.50487 -353.25939 -90)
		(property "Reference" "PC1187_P0_3"
			(at 0 0 90)
			(layer "B.SilkS")
			(hide yes)
			(effects
				(font
					(size 1.27 1.27)
				)
				(justify mirror)
			)
		)
		(property "Value" ""
			(at 0 0 90)
			(layer "B.Fab")
			(effects
				(font
					(size 1.27 1.27)
				)
				(justify mirror)
			)
		)
		(duplicate_pad_numbers_are_jumpers no)
		(fp_line
			(start -1.524 0.762)
			(end 1.524 0.762)
			(stroke
				(width 0.1524)
				(type default)
			)
			(layer "B.SilkS")
		)
		(fp_line
			(start 1.524 0.762)
			(end 1.524 -0.762)
			(stroke
				(width 0.1524)
				(type default)
			)
			(layer "B.SilkS")
		)
		(fp_line
			(start -1.524 -0.762)
			(end -1.524 0.762)
			(stroke
				(width 0.1524)
				(type default)
			)
			(layer "B.SilkS")
		)
		(fp_line
			(start 1.524 -0.762)
			(end -1.524 -0.762)
			(stroke
				(width 0.1524)
				(type default)
			)
			(layer "B.SilkS")
		)
		(fp_line
			(start -1.1049 0.724916)
			(end -1.1049 -0.724916)
			(stroke
				(width 0.1)
				(type default)
			)
			(layer "B.Fab")
		)
		(fp_line
			(start 1.1049 0.724916)
			(end -1.1049 0.724916)
			(stroke
				(width 0.1)
				(type default)
			)
			(layer "B.Fab")
		)
		(fp_line
			(start -1.1049 -0.724916)
			(end 1.1049 -0.724916)
			(stroke
				(width 0.1)
				(type default)
			)
			(layer "B.Fab")
		)
		(fp_line
			(start 1.1049 -0.724916)
			(end 1.1049 0.724916)
			(stroke
				(width 0.1)
				(type default)
			)
			(layer "B.Fab")
		)
		(pad "1" smd rect
			(at 0.889 0 270)
			(size 1.016 1.27)
			(layers "B.Cu" "B.Mask" "B.Paste")
			(net "PVCCFA_EHV_FIVRA_CPU0")
		)
		(pad "2" smd rect
			(at -0.889 0 270)
			(size 1.016 1.27)
			(layers "B.Cu" "B.Mask" "B.Paste")
			(net "GND")
		)
	)
	(footprint ""
		(layer "B.Cu")
		(at 328.142092 -66.244724 45)
		(property "Reference" "C1260"
			(at 0 0 45)
			(layer "B.SilkS")
			(hide yes)
			(effects
				(font
					(size 1.27 1.27)
				)
				(justify mirror)
			)
		)
		(property "Value" ""
			(at 0 0 45)
			(layer "B.Fab")
			(effects
				(font
					(size 1.27 1.27)
				)
				(justify mirror)
			)
		)
		(duplicate_pad_numbers_are_jumpers no)
		(fp_line
			(start -1.295492 -0.584255)
			(end -1.295492 0.584255)
			(stroke
				(width 0.1524)
				(type default)
			)
			(layer "B.SilkS")
		)
		(fp_line
			(start -1.295492 0.584255)
			(end 1.295492 0.584255)
			(stroke
				(width 0.1524)
				(type default)
			)
			(layer "B.SilkS")
		)
		(fp_line
			(start 0 -0.584076)
			(end 0 0.584076)
			(stroke
				(width 0.1524)
				(type default)
			)
			(layer "B.SilkS")
		)
		(fp_line
			(start 1.295492 -0.584255)
			(end -1.295492 -0.584255)
			(stroke
				(width 0.1524)
				(type default)
			)
			(layer "B.SilkS")
		)
		(fp_line
			(start 1.295492 0.584255)
			(end 1.295492 -0.584255)
			(stroke
				(width 0.1524)
				(type default)
			)
			(layer "B.SilkS")
		)
		(fp_line
			(start -1.193835 -0.406446)
			(end -1.193835 0.406446)
			(stroke
				(width 0.1)
				(type default)
			)
			(layer "B.Fab")
		)
		(fp_line
			(start -0.863541 -0.457275)
			(end -0.863721 -0.406446)
			(stroke
				(width 0.1)
				(type default)
			)
			(layer "B.Fab")
		)
		(fp_line
			(start -0.863721 -0.406446)
			(end -1.193835 -0.406446)
			(stroke
				(width 0.1)
				(type default)
			)
			(layer "B.Fab")
		)
		(fp_line
			(start -1.193835 0.406446)
			(end -0.863721 0.406446)
			(stroke
				(width 0.1)
				(type default)
			)
			(layer "B.Fab")
		)
		(fp_line
			(start -0.863721 0.406446)
			(end -0.863541 0.457275)
			(stroke
				(width 0.1)
				(type default)
			)
			(layer "B.Fab")
		)
		(fp_line
			(start -0.863541 0.457275)
			(end 0.863541 0.457275)
			(stroke
				(width 0.1)
				(type default)
			)
			(layer "B.Fab")
		)
		(fp_line
			(start 0.863541 -0.457275)
			(end -0.863541 -0.457275)
			(stroke
				(width 0.1)
				(type default)
			)
			(layer "B.Fab")
		)
		(fp_line
			(start 0.863721 -0.406446)
			(end 0.863541 -0.457275)
			(stroke
				(width 0.1)
				(type default)
			)
			(layer "B.Fab")
		)
		(fp_line
			(start 1.193835 -0.406446)
			(end 0.863721 -0.406446)
			(stroke
				(width 0.1)
				(type default)
			)
			(layer "B.Fab")
		)
		(fp_line
			(start 0.863721 0.406446)
			(end 1.193835 0.406446)
			(stroke
				(width 0.1)
				(type default)
			)
			(layer "B.Fab")
		)
		(fp_line
			(start 0.863541 0.457275)
			(end 0.863721 0.406446)
			(stroke
				(width 0.1)
				(type default)
			)
			(layer "B.Fab")
		)
		(fp_line
			(start 1.193835 0.406446)
			(end 1.193835 -0.406446)
			(stroke
				(width 0.1)
				(type default)
			)
			(layer "B.Fab")
		)
		(pad "1" smd rect
			(at 0.7366 0 315)
			(size 0.7112 0.8128)
			(layers "B.Cu" "B.Mask" "B.Paste")
			(net "P1V05_PCH_PLL_AUX")
		)
		(pad "2" smd rect
			(at -0.7366 0 315)
			(size 0.7112 0.8128)
			(layers "B.Cu" "B.Mask" "B.Paste")
			(net "GND")
		)
	)
)
